FILE_TYPE = CONNECTIVITY;
{Allegro Design Entry HDL 17.4-2019 S026 (4007227) 1/17/2022}
"PAGE_NUMBER" = 460;
0"NC";
1"P5E_CPU1_P3_RX_BUF_DP<7:0>";
2"P5E_CPU1_P3_RX_BUF_DN<7:0>";
3"P5E_CPU1_P3_RX_BUF_DN<15:8>";
4"P5E_CPU1_P3_RX_BUF_DP<15:8>";
5"P5E_CPU1_P3_RX_BUF_DP<12>";
6"P5E_CPU1_P3_RX_BUF_DP<11>";
7"P5E_CPU1_P3_RX_BUF_DN<12>";
8"P5E_CPU1_P3_RX_BUF_DN<11>";
9"P5E_CPU1_P3_RX_BUF_DP<10>";
10"P5E_CPU1_P3_RX_BUF_DN<9>";
11"P5E_CPU1_P3_RX_BUF_DP<9>";
12"P5E_CPU1_P3_RX_BUF_DP<1>";
13"P5E_CPU1_P3_RX_BUF_DP<4>";
14"P5E_CPU1_P3_RX_BUF_DN<4>";
15"P5E_CPU1_P3_RX_BUF_DP<5>";
16"P5E_CPU1_P3_RX_BUF_DP<2>";
17"P5E_CPU1_P3_RX_BUF_DN<3>";
18"P5E_CPU1_P3_RX_BUF_DP<3>";
19"P5E_CPU1_P3_RX_BUF_DN<13>";
20"P5E_CPU1_P3_RX_BUF_DN<15>";
21"P5E_CPU1_P3_RX_BUF_DP<15>";
22"P5E_CPU1_P3_RX_BUF_DP<8>";
23"P5E_CPU1_P3_RX_BUF_DN<10>";
24"P5E_CPU1_P3_RX_BUF_DP<13>";
25"P5E_CPU1_P3_RX_BUF_DN<14>";
26"P5E_CPU1_P3_RX_BUF_DP<14>";
27"P5E_CPU1_P3_RX_BUF_DN<8>";
28"P5E_CPU1_P3_RX_BUF_DP<0>";
29"P5E_CPU1_P3_RX_BUF_DN<1>";
30"P5E_CPU1_P3_RX_BUF_DN<2>";
31"P5E_CPU1_P3_RX_BUF_DN<5>";
32"P5E_CPU1_P3_RX_BUF_DN<6>";
33"P5E_CPU1_P3_RX_BUF_DP<6>";
34"P5E_CPU1_P3_RX_BUF_DN<0>";
35"P5E_CPU1_P3_RX_BUF_DN<7>";
36"P5E_CPU1_P3_RX_BUF_DP<7>";
%"PT5161LRS"
"1","(-7775,3750)","0","pure_quanta","I1";
;
LOCATION"U6017"
$SEC"1"
CDS_SEC"1"
VALUE"PT5161LRS"
PART_TYPE"SMLF"
MATERIAL"IC"
NEEDS_NO_SIZE"TRUE"
CDS_LMAN_SYM_OUTLINE"-350,1450,300,-1400"
CDS_LIB"pure_quanta"
PART_NUMBER"AJ051610U03";
"A_PERN7"
$PN"CB2"27;
"A_PERP7"
$PN"CD1"22;
"A_PERN6"
$PN"BR2"10;
"A_PERP6"
$PN"BU1"11;
"A_PERN5"
$PN"BH2"23;
"A_PERP5"
$PN"BK1"9;
"A_PERN4"
$PN"BA2"8;
"A_PERP4"
$PN"BC1"6;
"A_PERN3"
$PN"AP2"7;
"A_PERP3"
$PN"AT1"5;
"A_PERN2"
$PN"AG2"19;
"A_PERP2"
$PN"AJ1"24;
"A_PERN1"
$PN"Y2"25;
"A_PERP1"
$PN"AB1"26;
"A_PERN0"
$PN"N2"20;
"A_PERP0"
$PN"R1"21;
%"TAP"
"1","(-6550,3500)","0","standard","I10";
;
CDS_LIB"standard"
BODY_TYPE"PLUMBING"
HDL_TAP"TRUE";
"B \NAC \NWC"3;
"S \NAC"
BN"11"8;
%"TAP"
"1","(-6550,3850)","0","standard","I11";
;
CDS_LIB"standard"
BODY_TYPE"PLUMBING"
HDL_TAP"TRUE";
"B \NAC \NWC"3;
"S \NAC"
BN"12"7;
%"TAP"
"1","(-6750,4300)","0","standard","I12";
;
CDS_LIB"standard"
BODY_TYPE"PLUMBING"
HDL_TAP"TRUE";
"B \NAC \NWC"4;
"S \NAC"
BN"13"24;
%"TAP"
"1","(-6750,4650)","0","standard","I13";
;
CDS_LIB"standard"
BODY_TYPE"PLUMBING"
HDL_TAP"TRUE";
"B \NAC \NWC"4;
"S \NAC"
BN"14"26;
%"TAP"
"1","(-6750,5000)","0","standard","I14";
;
CDS_LIB"standard"
BODY_TYPE"PLUMBING"
HDL_TAP"TRUE";
"B \NAC \NWC"4;
"S \NAC"
BN"15"21;
%"TAP"
"1","(-6550,4200)","0","standard","I15";
;
CDS_LIB"standard"
BODY_TYPE"PLUMBING"
HDL_TAP"TRUE";
"B \NAC \NWC"3;
"S \NAC"
BN"13"19;
%"TAP"
"1","(-6550,4550)","0","standard","I16";
;
CDS_LIB"standard"
BODY_TYPE"PLUMBING"
HDL_TAP"TRUE";
"B \NAC \NWC"3;
"S \NAC"
BN"14"25;
%"TAP"
"1","(-6550,4900)","0","standard","I17";
;
CDS_LIB"standard"
BODY_TYPE"PLUMBING"
HDL_TAP"TRUE";
"B \NAC \NWC"3;
"S \NAC"
BN"15"20;
%"TAP"
"1","(-6750,2550)","0","standard","I2";
;
CDS_LIB"standard"
BODY_TYPE"PLUMBING"
HDL_TAP"TRUE";
"B \NAC \NWC"4;
"S \NAC"
BN"8"22;
%"TAP"
"1","(-2300,2575)","0","standard","I20";
;
CDS_LIB"standard"
BODY_TYPE"PLUMBING"
HDL_TAP"TRUE";
"B \NAC \NWC"1;
"S \NAC"
BN"0"28;
%"TAP"
"1","(-2300,2925)","0","standard","I21";
;
CDS_LIB"standard"
BODY_TYPE"PLUMBING"
HDL_TAP"TRUE";
"B \NAC \NWC"1;
"S \NAC"
BN"1"12;
%"TAP"
"1","(-2100,2475)","0","standard","I22";
;
CDS_LIB"standard"
BODY_TYPE"PLUMBING"
HDL_TAP"TRUE";
"B \NAC \NWC"2;
"S \NAC"
BN"0"34;
%"TAP"
"1","(-2100,2825)","0","standard","I23";
;
CDS_LIB"standard"
BODY_TYPE"PLUMBING"
HDL_TAP"TRUE";
"B \NAC \NWC"2;
"S \NAC"
BN"1"29;
%"TAP"
"1","(-2300,3275)","0","standard","I24";
;
CDS_LIB"standard"
BODY_TYPE"PLUMBING"
HDL_TAP"TRUE";
"B \NAC \NWC"1;
"S \NAC"
BN"2"16;
%"TAP"
"1","(-2100,3175)","0","standard","I25";
;
CDS_LIB"standard"
BODY_TYPE"PLUMBING"
HDL_TAP"TRUE";
"B \NAC \NWC"2;
"S \NAC"
BN"2"30;
%"TAP"
"1","(-2300,3625)","0","standard","I26";
;
CDS_LIB"standard"
BODY_TYPE"PLUMBING"
HDL_TAP"TRUE";
"B \NAC \NWC"1;
"S \NAC"
BN"3"18;
%"TAP"
"1","(-2300,3975)","0","standard","I27";
;
CDS_LIB"standard"
BODY_TYPE"PLUMBING"
HDL_TAP"TRUE";
"B \NAC \NWC"1;
"S \NAC"
BN"4"13;
%"TAP"
"1","(-2100,3525)","0","standard","I28";
;
CDS_LIB"standard"
BODY_TYPE"PLUMBING"
HDL_TAP"TRUE";
"B \NAC \NWC"2;
"S \NAC"
BN"3"17;
%"TAP"
"1","(-2100,3875)","0","standard","I29";
;
CDS_LIB"standard"
BODY_TYPE"PLUMBING"
HDL_TAP"TRUE";
"B \NAC \NWC"2;
"S \NAC"
BN"4"14;
%"TAP"
"1","(-6750,2900)","0","standard","I3";
;
CDS_LIB"standard"
BODY_TYPE"PLUMBING"
HDL_TAP"TRUE";
"B \NAC \NWC"4;
"S \NAC"
BN"9"11;
%"TAP"
"1","(-2300,4325)","0","standard","I30";
;
CDS_LIB"standard"
BODY_TYPE"PLUMBING"
HDL_TAP"TRUE";
"B \NAC \NWC"1;
"S \NAC"
BN"5"15;
%"TAP"
"1","(-2100,4225)","0","standard","I31";
;
CDS_LIB"standard"
BODY_TYPE"PLUMBING"
HDL_TAP"TRUE";
"B \NAC \NWC"2;
"S \NAC"
BN"5"31;
%"TAP"
"1","(-2300,4675)","0","standard","I32";
;
CDS_LIB"standard"
BODY_TYPE"PLUMBING"
HDL_TAP"TRUE";
"B \NAC \NWC"1;
"S \NAC"
BN"6"33;
%"TAP"
"1","(-2100,4575)","0","standard","I33";
;
CDS_LIB"standard"
BODY_TYPE"PLUMBING"
HDL_TAP"TRUE";
"B \NAC \NWC"2;
"S \NAC"
BN"6"32;
%"TAP"
"1","(-2100,4925)","0","standard","I34";
;
CDS_LIB"standard"
BODY_TYPE"PLUMBING"
HDL_TAP"TRUE";
"B \NAC \NWC"2;
"S \NAC"
BN"7"35;
%"TAP"
"1","(-2300,5025)","0","standard","I35";
;
CDS_LIB"standard"
BODY_TYPE"PLUMBING"
HDL_TAP"TRUE";
"B \NAC \NWC"1;
"S \NAC"
BN"7"36;
%"PT5161LRS"
"2","(-3325,3775)","0","pure_quanta","I38";
;
LOCATION"U6017"
$SEC"2"
CDS_SEC"2"
PART_TYPE"SMLF"
VALUE"PT5161LRS"
MATERIAL"IC"
CDS_LIB"pure_quanta"
CDS_LMAN_SYM_OUTLINE"-350,1450,300,-1400"
NEEDS_NO_SIZE"TRUE"
PART_NUMBER"AJ051610U03";
"A_PERN15"
$PN"EV2"34;
"A_PERP15"
$PN"EY1"28;
"A_PERN14"
$PN"EL2"29;
"A_PERP14"
$PN"EN1"12;
"A_PERN13"
$PN"ED2"30;
"A_PERP13"
$PN"EF1"16;
"A_PERN12"
$PN"DU2"17;
"A_PERP12"
$PN"DW1"18;
"A_PERN11"
$PN"DK2"14;
"A_PERP11"
$PN"DM1"13;
"A_PERN10"
$PN"DC2"31;
"A_PERP10"
$PN"DE1"15;
"A_PERN9"
$PN"CT2"32;
"A_PERP9"
$PN"CV1"33;
"A_PERN8"
$PN"CJ2"35;
"A_PERP8"
$PN"CL1"36;
%"TAP"
"1","(-6550,2450)","0","standard","I4";
;
CDS_LIB"standard"
BODY_TYPE"PLUMBING"
HDL_TAP"TRUE";
"B \NAC \NWC"3;
"S \NAC"
BN"8"27;
%"TAP"
"1","(-6550,2800)","0","standard","I5";
;
CDS_LIB"standard"
BODY_TYPE"PLUMBING"
HDL_TAP"TRUE";
"B \NAC \NWC"3;
"S \NAC"
BN"9"10;
%"TAP"
"1","(-6750,3250)","0","standard","I6";
;
CDS_LIB"standard"
BODY_TYPE"PLUMBING"
HDL_TAP"TRUE";
"B \NAC \NWC"4;
"S \NAC"
BN"10"9;
%"TAP"
"1","(-6750,3600)","0","standard","I7";
;
CDS_LIB"standard"
BODY_TYPE"PLUMBING"
HDL_TAP"TRUE";
"B \NAC \NWC"4;
"S \NAC"
BN"11"6;
%"TAP"
"1","(-6750,3950)","0","standard","I8";
;
CDS_LIB"standard"
BODY_TYPE"PLUMBING"
HDL_TAP"TRUE";
"B \NAC \NWC"4;
"S \NAC"
BN"12"5;
%"TAP"
"1","(-6550,3150)","0","standard","I9";
;
CDS_LIB"standard"
BODY_TYPE"PLUMBING"
HDL_TAP"TRUE";
"B \NAC \NWC"3;
"S \NAC"
BN"10"23;
END.
